(kicad_pcb
	(version 20260206)
	(generator "pcbnew")
	(generator_version "10.0")
	(general
		(thickness 1.6)
		(legacy_teardrops no)
	)
	(paper "A4")
	(title_block
		(title "04192023_DAF0TMB3IC0_F0TG_MB_C_brd_V02_OCP.brd")
		(comment 1 "Grand Teton / footprints 3078-3085 of 8354")
	)
	(layers
		(0 "F.Cu" signal "TOP")
		(4 "In1.Cu" signal "GND")
		(6 "In2.Cu" signal "IN1")
		(8 "In3.Cu" signal "GND1")
		(10 "In4.Cu" signal "IN2")
		(12 "In5.Cu" signal "GND2")
		(14 "In6.Cu" signal "IN3")
		(16 "In7.Cu" signal "GND3")
		(18 "In8.Cu" signal "VCC")
		(20 "In9.Cu" signal "VCC1")
		(22 "In10.Cu" signal "GND4")
		(24 "In11.Cu" signal "IN4")
		(26 "In12.Cu" signal "GND5")
		(28 "In13.Cu" signal "IN5")
		(30 "In14.Cu" signal "GND6")
		(32 "In15.Cu" signal "IN6")
		(34 "In16.Cu" signal "GND7")
		(2 "B.Cu" signal "BOTTOM")
		(9 "F.Adhes" user "F.Adhesive")
		(11 "B.Adhes" user "B.Adhesive")
		(13 "F.Paste" user "Package Geometry/Pastemask Top")
		(15 "B.Paste" user "Package Geometry/Pastemask Bottom")
		(5 "F.SilkS" user "Ref Des/Silkscreen Top")
		(7 "B.SilkS" user "Ref Des/Silkscreen Bottom")
		(1 "F.Mask" user "Board Geometry/Soldermask Top")
		(3 "B.Mask" user "Board Geometry/Soldermask Bottom")
		(17 "Dwgs.User" user "User.Drawings")
		(19 "Cmts.User" user "User.Comments")
		(21 "Eco1.User" user "User.Eco1")
		(23 "Eco2.User" user "User.Eco2")
		(25 "Edge.Cuts" user "Board Geometry/Outline")
		(27 "Margin" user)
		(31 "F.CrtYd" user "Package Geometry/Place Bound Top")
		(29 "B.CrtYd" user "Package Geometry/Place Bound Bottom")
		(35 "F.Fab" user "Ref Des/Assembly Top")
		(33 "B.Fab" user "Ref Des/Assembly Bottom")
	)
	(footprint ""
		(layer "F.Cu")
		(at 163.703 -111.216948 180)
		(property "Reference" "R6094"
			(at 0 0 180)
			(layer "F.SilkS")
			(hide yes)
			(effects
				(font
					(size 1.27 1.27)
				)
			)
		)
		(property "Value" ""
			(at 0 0 180)
			(layer "F.Fab")
			(effects
				(font
					(size 1.27 1.27)
				)
			)
		)
		(duplicate_pad_numbers_are_jumpers no)
		(fp_line
			(start 0.7874 0.4064)
			(end -0.7874 0.4064)
			(stroke
				(width 0.1524)
				(type default)
			)
			(layer "F.SilkS")
		)
		(fp_line
			(start 0.7874 -0.4064)
			(end 0.7874 0.4064)
			(stroke
				(width 0.1524)
				(type default)
			)
			(layer "F.SilkS")
		)
		(fp_line
			(start -0.7874 0.4064)
			(end -0.7874 -0.4064)
			(stroke
				(width 0.1524)
				(type default)
			)
			(layer "F.SilkS")
		)
		(fp_line
			(start -0.7874 -0.4064)
			(end 0.7874 -0.4064)
			(stroke
				(width 0.1524)
				(type default)
			)
			(layer "F.SilkS")
		)
		(fp_line
			(start 0.67945 0.3048)
			(end 0.120396 0.3048)
			(stroke
				(width 0.1)
				(type default)
			)
			(layer "F.Fab")
		)
		(fp_line
			(start 0.67945 -0.3048)
			(end 0.67945 0.3048)
			(stroke
				(width 0.1)
				(type default)
			)
			(layer "F.Fab")
		)
		(fp_line
			(start 0.12065 -0.2794)
			(end 0.12065 -0.3048)
			(stroke
				(width 0.1)
				(type default)
			)
			(layer "F.Fab")
		)
		(fp_line
			(start 0.12065 -0.3048)
			(end 0.67945 -0.3048)
			(stroke
				(width 0.1)
				(type default)
			)
			(layer "F.Fab")
		)
		(fp_line
			(start 0.120396 0.3048)
			(end 0.120396 0.2794)
			(stroke
				(width 0.1)
				(type default)
			)
			(layer "F.Fab")
		)
		(fp_line
			(start 0.120396 0.2794)
			(end -0.12065 0.2794)
			(stroke
				(width 0.1)
				(type default)
			)
			(layer "F.Fab")
		)
		(fp_line
			(start -0.12065 0.3048)
			(end -0.67945 0.3048)
			(stroke
				(width 0.1)
				(type default)
			)
			(layer "F.Fab")
		)
		(fp_line
			(start -0.12065 0.2794)
			(end -0.12065 0.3048)
			(stroke
				(width 0.1)
				(type default)
			)
			(layer "F.Fab")
		)
		(fp_line
			(start -0.12065 -0.2794)
			(end 0.12065 -0.2794)
			(stroke
				(width 0.1)
				(type default)
			)
			(layer "F.Fab")
		)
		(fp_line
			(start -0.12065 -0.305054)
			(end -0.12065 -0.2794)
			(stroke
				(width 0.1)
				(type default)
			)
			(layer "F.Fab")
		)
		(fp_line
			(start -0.67945 0.3048)
			(end -0.67945 -0.305054)
			(stroke
				(width 0.1)
				(type default)
			)
			(layer "F.Fab")
		)
		(fp_line
			(start -0.67945 -0.305054)
			(end -0.12065 -0.305054)
			(stroke
				(width 0.1)
				(type default)
			)
			(layer "F.Fab")
		)
		(pad "1" smd circle
			(at -0.40005 0 180)
			(size 0 0)
			(layers "F.Cu" "F.Mask" "F.Paste")
			(net "E1S_0_PERST1_CLKREQ_R_N")
		)
		(pad "2" smd circle
			(at 0.40005 0 180)
			(size 0 0)
			(layers "F.Cu" "F.Mask" "F.Paste")
			(net "E1S_0_PERST1_CLKREQ_N")
		)
	)
	(footprint ""
		(layer "F.Cu")
		(at 93.582998 -47.049944 90)
		(property "Reference" "H75"
			(at -3.856482 -4.516374 0)
			(unlocked yes)
			(layer "F.SilkS")
			(effects
				(font
					(size 0.7874 0.5842)
					(thickness 0.1524)
				)
			)
		)
		(property "Value" ""
			(at 0 0 90)
			(layer "F.Fab")
			(effects
				(font
					(size 1.27 1.27)
				)
			)
		)
		(duplicate_pad_numbers_are_jumpers no)
		(pad "" np_thru_hole circle
			(at 0 0 90)
			(size 0 0)
			(drill oval 3.2004 4.8006)
			(layers "*.Cu" "*.Mask")
			(clearance -1.2192)
			(thermal_gap 0.381)
			(padstack
				(mode front_inner_back)
				(layer "Inner"
					(shape oval)
					(size 3.2004 4.8006)
					(clearance 0.381)
				)
				(layer "B.Cu"
					(shape circle)
					(size 0 0)
					(clearance -1.2192)
				)
			)
		)
		(zone
			(layers "F.Cu" "B.Cu" "In1.Cu" "In2.Cu" "In3.Cu" "In4.Cu" "In5.Cu" "In6.Cu"
				"In7.Cu" "In8.Cu" "In9.Cu" "In10.Cu" "In11.Cu" "In12.Cu" "In13.Cu" "In14.Cu"
				"In15.Cu" "In16.Cu"
			)
			(hatch none 0.5)
			(connect_pads
				(clearance 0)
			)
			(min_thickness 0.25)
			(keepout
				(tracks not_allowed)
				(vias allowed)
				(pads allowed)
				(copperpour not_allowed)
				(footprints allowed)
			)
			(placement
				(enabled no)
				(sheetname "")
			)
			(fill
				(thermal_gap 0.5)
				(thermal_bridge_width 0.5)
				(island_removal_mode 0)
			)
			(polygon
				(pts
					(arc
						(start 94.383098 -49.158144)
						(mid 96.491298 -47.049944)
						(end 94.383098 -44.941744)
					)
					(arc
						(start 92.782898 -44.941744)
						(mid 90.674698 -47.049944)
						(end 92.782898 -49.158144)
					)
				)
			)
		)
		(zone
			(layers "F.Cu" "B.Cu" "In1.Cu" "In2.Cu" "In3.Cu" "In4.Cu" "In5.Cu" "In6.Cu"
				"In7.Cu" "In8.Cu" "In9.Cu" "In10.Cu" "In11.Cu" "In12.Cu" "In13.Cu" "In14.Cu"
				"In15.Cu" "In16.Cu"
			)
			(hatch none 0.5)
			(connect_pads
				(clearance 0)
			)
			(min_thickness 0.25)
			(keepout
				(tracks not_allowed)
				(vias allowed)
				(pads allowed)
				(copperpour not_allowed)
				(footprints allowed)
			)
			(placement
				(enabled no)
				(sheetname "")
			)
			(fill
				(thermal_gap 0.5)
				(thermal_bridge_width 0.5)
				(island_removal_mode 0)
			)
			(polygon
				(pts
					(arc
						(start 94.383098 -50.050192)
						(mid 97.383346 -47.049944)
						(end 94.383098 -44.049696)
					)
					(arc
						(start 92.782898 -44.049696)
						(mid 89.78265 -47.049944)
						(end 92.782898 -50.050192)
					)
				)
			)
		)
	)
	(footprint ""
		(layer "F.Cu")
		(at 147.722844 -375.49963 -90)
		(property "Reference" "C765"
			(at 0 0 270)
			(layer "F.SilkS")
			(hide yes)
			(effects
				(font
					(size 1.27 1.27)
				)
			)
		)
		(property "Value" ""
			(at 0 0 270)
			(layer "F.Fab")
			(effects
				(font
					(size 1.27 1.27)
				)
			)
		)
		(duplicate_pad_numbers_are_jumpers no)
		(fp_line
			(start -0.299974 0.150114)
			(end -0.299974 -0.150114)
			(stroke
				(width 0.1)
				(type default)
			)
			(layer "F.Fab")
		)
		(fp_line
			(start 0.299974 0.150114)
			(end -0.299974 0.150114)
			(stroke
				(width 0.1)
				(type default)
			)
			(layer "F.Fab")
		)
		(fp_line
			(start -0.299974 -0.150114)
			(end 0.299974 -0.150114)
			(stroke
				(width 0.1)
				(type default)
			)
			(layer "F.Fab")
		)
		(fp_line
			(start 0.299974 -0.150114)
			(end 0.299974 0.150114)
			(stroke
				(width 0.1)
				(type default)
			)
			(layer "F.Fab")
		)
		(pad "1" smd rect
			(at -0.2667 0 270)
			(size 0.3048 0.381)
			(layers "F.Cu" "F.Mask" "F.Paste")
			(net "P5E_CPU1_P2_TX_C_DP<4>")
		)
		(pad "2" smd rect
			(at 0.2667 0 270)
			(size 0.3048 0.381)
			(layers "F.Cu" "F.Mask" "F.Paste")
			(net "P5E_CPU1_P2_TX_DP<4>")
		)
	)
	(footprint ""
		(layer "F.Cu")
		(at 150.420324 -115.377468)
		(property "Reference" "R8119"
			(at 0 0 0)
			(layer "F.SilkS")
			(hide yes)
			(effects
				(font
					(size 1.27 1.27)
				)
			)
		)
		(property "Value" ""
			(at 0 0 0)
			(layer "F.Fab")
			(effects
				(font
					(size 1.27 1.27)
				)
			)
		)
		(duplicate_pad_numbers_are_jumpers no)
		(fp_line
			(start -0.7874 -0.4064)
			(end 0.7874 -0.4064)
			(stroke
				(width 0.1524)
				(type default)
			)
			(layer "F.SilkS")
		)
		(fp_line
			(start -0.7874 0.4064)
			(end -0.7874 -0.4064)
			(stroke
				(width 0.1524)
				(type default)
			)
			(layer "F.SilkS")
		)
		(fp_line
			(start 0.7874 -0.4064)
			(end 0.7874 0.4064)
			(stroke
				(width 0.1524)
				(type default)
			)
			(layer "F.SilkS")
		)
		(fp_line
			(start 0.7874 0.4064)
			(end -0.7874 0.4064)
			(stroke
				(width 0.1524)
				(type default)
			)
			(layer "F.SilkS")
		)
		(fp_line
			(start -0.67945 -0.305054)
			(end -0.12065 -0.305054)
			(stroke
				(width 0.1)
				(type default)
			)
			(layer "F.Fab")
		)
		(fp_line
			(start -0.67945 0.3048)
			(end -0.67945 -0.305054)
			(stroke
				(width 0.1)
				(type default)
			)
			(layer "F.Fab")
		)
		(fp_line
			(start -0.12065 -0.305054)
			(end -0.12065 -0.2794)
			(stroke
				(width 0.1)
				(type default)
			)
			(layer "F.Fab")
		)
		(fp_line
			(start -0.12065 -0.2794)
			(end 0.12065 -0.2794)
			(stroke
				(width 0.1)
				(type default)
			)
			(layer "F.Fab")
		)
		(fp_line
			(start -0.12065 0.2794)
			(end -0.12065 0.3048)
			(stroke
				(width 0.1)
				(type default)
			)
			(layer "F.Fab")
		)
		(fp_line
			(start -0.12065 0.3048)
			(end -0.67945 0.3048)
			(stroke
				(width 0.1)
				(type default)
			)
			(layer "F.Fab")
		)
		(fp_line
			(start 0.120396 0.2794)
			(end -0.12065 0.2794)
			(stroke
				(width 0.1)
				(type default)
			)
			(layer "F.Fab")
		)
		(fp_line
			(start 0.120396 0.3048)
			(end 0.120396 0.2794)
			(stroke
				(width 0.1)
				(type default)
			)
			(layer "F.Fab")
		)
		(fp_line
			(start 0.12065 -0.3048)
			(end 0.67945 -0.3048)
			(stroke
				(width 0.1)
				(type default)
			)
			(layer "F.Fab")
		)
		(fp_line
			(start 0.12065 -0.2794)
			(end 0.12065 -0.3048)
			(stroke
				(width 0.1)
				(type default)
			)
			(layer "F.Fab")
		)
		(fp_line
			(start 0.67945 -0.3048)
			(end 0.67945 0.3048)
			(stroke
				(width 0.1)
				(type default)
			)
			(layer "F.Fab")
		)
		(fp_line
			(start 0.67945 0.3048)
			(end 0.120396 0.3048)
			(stroke
				(width 0.1)
				(type default)
			)
			(layer "F.Fab")
		)
		(pad "1" smd circle
			(at -0.40005 0)
			(size 0 0)
			(layers "F.Cu" "F.Mask" "F.Paste")
			(net "P3V3_AUX")
		)
		(pad "2" smd circle
			(at 0.40005 0)
			(size 0 0)
			(layers "F.Cu" "F.Mask" "F.Paste")
			(net "FM_UV_ADR_TRIGGER_N")
		)
	)
	(footprint ""
		(layer "F.Cu")
		(at 74.2696 -383.7432)
		(property "Reference" "R788"
			(at 0 0 0)
			(layer "F.SilkS")
			(hide yes)
			(effects
				(font
					(size 1.27 1.27)
				)
			)
		)
		(property "Value" ""
			(at 0 0 0)
			(layer "F.Fab")
			(effects
				(font
					(size 1.27 1.27)
				)
			)
		)
		(duplicate_pad_numbers_are_jumpers no)
		(fp_line
			(start -0.32512 -0.175006)
			(end 0.32512 -0.175006)
			(stroke
				(width 0.1)
				(type default)
			)
			(layer "F.Fab")
		)
		(fp_line
			(start -0.32512 0.175006)
			(end -0.32512 -0.175006)
			(stroke
				(width 0.1)
				(type default)
			)
			(layer "F.Fab")
		)
		(fp_line
			(start 0.32512 -0.175006)
			(end 0.32512 0.175006)
			(stroke
				(width 0.1)
				(type default)
			)
			(layer "F.Fab")
		)
		(fp_line
			(start 0.32512 0.175006)
			(end -0.32512 0.175006)
			(stroke
				(width 0.1)
				(type default)
			)
			(layer "F.Fab")
		)
		(pad "1" smd rect
			(at -0.2667 0)
			(size 0.3048 0.381)
			(layers "F.Cu" "F.Mask" "F.Paste")
			(net "P1V8_CPU1_RT_1D")
		)
		(pad "2" smd rect
			(at 0.2667 0 180)
			(size 0.3048 0.381)
			(layers "F.Cu" "F.Mask" "F.Paste")
			(net "TEST2_RT_CPU1_P1")
		)
	)
	(footprint ""
		(layer "F.Cu")
		(at 23.816818 -435.925214 180)
		(property "Reference" "C1796"
			(at 0 0 180)
			(layer "F.SilkS")
			(hide yes)
			(effects
				(font
					(size 1.27 1.27)
				)
			)
		)
		(property "Value" ""
			(at 0 0 180)
			(layer "F.Fab")
			(effects
				(font
					(size 1.27 1.27)
				)
			)
		)
		(duplicate_pad_numbers_are_jumpers no)
		(fp_line
			(start 0.7874 0.4064)
			(end -0.7874 0.4064)
			(stroke
				(width 0.1524)
				(type default)
			)
			(layer "F.SilkS")
		)
		(fp_line
			(start 0.7874 -0.4064)
			(end 0.7874 0.4064)
			(stroke
				(width 0.1524)
				(type default)
			)
			(layer "F.SilkS")
		)
		(fp_line
			(start -0.7874 0.4064)
			(end -0.7874 -0.4064)
			(stroke
				(width 0.1524)
				(type default)
			)
			(layer "F.SilkS")
		)
		(fp_line
			(start -0.7874 -0.4064)
			(end 0.7874 -0.4064)
			(stroke
				(width 0.1524)
				(type default)
			)
			(layer "F.SilkS")
		)
		(fp_line
			(start 0.67945 0.3048)
			(end 0.120396 0.3048)
			(stroke
				(width 0.1)
				(type default)
			)
			(layer "F.Fab")
		)
		(fp_line
			(start 0.67945 -0.3048)
			(end 0.67945 0.3048)
			(stroke
				(width 0.1)
				(type default)
			)
			(layer "F.Fab")
		)
		(fp_line
			(start 0.12065 -0.2794)
			(end 0.12065 -0.3048)
			(stroke
				(width 0.1)
				(type default)
			)
			(layer "F.Fab")
		)
		(fp_line
			(start 0.12065 -0.3048)
			(end 0.67945 -0.3048)
			(stroke
				(width 0.1)
				(type default)
			)
			(layer "F.Fab")
		)
		(fp_line
			(start 0.120396 0.3048)
			(end 0.120396 0.2794)
			(stroke
				(width 0.1)
				(type default)
			)
			(layer "F.Fab")
		)
		(fp_line
			(start 0.120396 0.2794)
			(end -0.12065 0.2794)
			(stroke
				(width 0.1)
				(type default)
			)
			(layer "F.Fab")
		)
		(fp_line
			(start -0.12065 0.3048)
			(end -0.67945 0.3048)
			(stroke
				(width 0.1)
				(type default)
			)
			(layer "F.Fab")
		)
		(fp_line
			(start -0.12065 0.2794)
			(end -0.12065 0.3048)
			(stroke
				(width 0.1)
				(type default)
			)
			(layer "F.Fab")
		)
		(fp_line
			(start -0.12065 -0.2794)
			(end 0.12065 -0.2794)
			(stroke
				(width 0.1)
				(type default)
			)
			(layer "F.Fab")
		)
		(fp_line
			(start -0.12065 -0.305054)
			(end -0.12065 -0.2794)
			(stroke
				(width 0.1)
				(type default)
			)
			(layer "F.Fab")
		)
		(fp_line
			(start -0.67945 0.3048)
			(end -0.67945 -0.305054)
			(stroke
				(width 0.1)
				(type default)
			)
			(layer "F.Fab")
		)
		(fp_line
			(start -0.67945 -0.305054)
			(end -0.12065 -0.305054)
			(stroke
				(width 0.1)
				(type default)
			)
			(layer "F.Fab")
		)
		(pad "1" smd circle
			(at -0.40005 0 180)
			(size 0 0)
			(layers "F.Cu" "F.Mask" "F.Paste")
			(net "P3V3_AUX")
		)
		(pad "2" smd circle
			(at 0.40005 0 180)
			(size 0 0)
			(layers "F.Cu" "F.Mask" "F.Paste")
			(net "GND")
		)
	)
	(footprint ""
		(layer "F.Cu")
		(at 99.08794 -335.179416 -90)
		(property "Reference" "PC424_5"
			(at 0 0 270)
			(layer "F.SilkS")
			(hide yes)
			(effects
				(font
					(size 1.27 1.27)
				)
			)
		)
		(property "Value" ""
			(at 0 0 270)
			(layer "F.Fab")
			(effects
				(font
					(size 1.27 1.27)
				)
			)
		)
		(duplicate_pad_numbers_are_jumpers no)
		(fp_line
			(start -0.7874 0.4064)
			(end -0.7874 -0.4064)
			(stroke
				(width 0.1524)
				(type default)
			)
			(layer "F.SilkS")
		)
		(fp_line
			(start 0.7874 0.4064)
			(end -0.7874 0.4064)
			(stroke
				(width 0.1524)
				(type default)
			)
			(layer "F.SilkS")
		)
		(fp_line
			(start -0.7874 -0.4064)
			(end 0.7874 -0.4064)
			(stroke
				(width 0.1524)
				(type default)
			)
			(layer "F.SilkS")
		)
		(fp_line
			(start 0.7874 -0.4064)
			(end 0.7874 0.4064)
			(stroke
				(width 0.1524)
				(type default)
			)
			(layer "F.SilkS")
		)
		(fp_line
			(start -0.67945 0.3048)
			(end -0.67945 -0.305054)
			(stroke
				(width 0.1)
				(type default)
			)
			(layer "F.Fab")
		)
		(fp_line
			(start -0.12065 0.3048)
			(end -0.67945 0.3048)
			(stroke
				(width 0.1)
				(type default)
			)
			(layer "F.Fab")
		)
		(fp_line
			(start 0.120396 0.3048)
			(end 0.120396 0.2794)
			(stroke
				(width 0.1)
				(type default)
			)
			(layer "F.Fab")
		)
		(fp_line
			(start 0.67945 0.3048)
			(end 0.120396 0.3048)
			(stroke
				(width 0.1)
				(type default)
			)
			(layer "F.Fab")
		)
		(fp_line
			(start -0.12065 0.2794)
			(end -0.12065 0.3048)
			(stroke
				(width 0.1)
				(type default)
			)
			(layer "F.Fab")
		)
		(fp_line
			(start 0.120396 0.2794)
			(end -0.12065 0.2794)
			(stroke
				(width 0.1)
				(type default)
			)
			(layer "F.Fab")
		)
		(fp_line
			(start -0.12065 -0.2794)
			(end 0.12065 -0.2794)
			(stroke
				(width 0.1)
				(type default)
			)
			(layer "F.Fab")
		)
		(fp_line
			(start 0.12065 -0.2794)
			(end 0.12065 -0.3048)
			(stroke
				(width 0.1)
				(type default)
			)
			(layer "F.Fab")
		)
		(fp_line
			(start 0.12065 -0.3048)
			(end 0.67945 -0.3048)
			(stroke
				(width 0.1)
				(type default)
			)
			(layer "F.Fab")
		)
		(fp_line
			(start 0.67945 -0.3048)
			(end 0.67945 0.3048)
			(stroke
				(width 0.1)
				(type default)
			)
			(layer "F.Fab")
		)
		(fp_line
			(start -0.67945 -0.305054)
			(end -0.12065 -0.305054)
			(stroke
				(width 0.1)
				(type default)
			)
			(layer "F.Fab")
		)
		(fp_line
			(start -0.12065 -0.305054)
			(end -0.12065 -0.2794)
			(stroke
				(width 0.1)
				(type default)
			)
			(layer "F.Fab")
		)
		(pad "1" smd circle
			(at -0.40005 0 270)
			(size 0 0)
			(layers "F.Cu" "F.Mask" "F.Paste")
			(net "SW_P12V_AUX_PVDDCR_CPU1_P1_FLT")
		)
		(pad "2" smd circle
			(at 0.40005 0 270)
			(size 0 0)
			(layers "F.Cu" "F.Mask" "F.Paste")
			(net "GND")
		)
	)
	(footprint ""
		(layer "F.Cu")
		(at 99.509834 -136.179052)
		(property "Reference" "PQ15"
			(at 1.15316 2.498852 0)
			(unlocked yes)
			(layer "F.SilkS")
			(effects
				(font
					(size 0.7874 0.5842)
					(thickness 0.1524)
				)
			)
		)
		(property "Value" ""
			(at 0 0 0)
			(layer "F.Fab")
			(effects
				(font
					(size 1.27 1.27)
				)
			)
		)
		(duplicate_pad_numbers_are_jumpers no)
		(fp_line
			(start -1.949958 -1.610106)
			(end 1.949958 -1.610106)
			(stroke
				(width 0.1524)
				(type default)
			)
			(layer "F.SilkS")
		)
		(fp_line
			(start -1.949958 1.610106)
			(end -1.949958 -1.610106)
			(stroke
				(width 0.1524)
				(type default)
			)
			(layer "F.SilkS")
		)
		(fp_line
			(start 1.949958 -1.560068)
			(end 1.949958 1.610106)
			(stroke
				(width 0.1524)
				(type default)
			)
			(layer "F.SilkS")
		)
		(fp_line
			(start 1.949958 1.610106)
			(end -1.949958 1.610106)
			(stroke
				(width 0.1524)
				(type default)
			)
			(layer "F.SilkS")
		)
		(fp_line
			(start -0.750062 -1.560068)
			(end 0.750062 -1.560068)
			(stroke
				(width 0.1)
				(type default)
			)
			(layer "F.Fab")
		)
		(fp_line
			(start -0.750062 1.560068)
			(end -0.750062 -1.560068)
			(stroke
				(width 0.1)
				(type default)
			)
			(layer "F.Fab")
		)
		(fp_line
			(start 0.750062 -1.560068)
			(end 0.750062 1.560068)
			(stroke
				(width 0.1)
				(type default)
			)
			(layer "F.Fab")
		)
		(fp_line
			(start 0.750062 1.560068)
			(end -0.750062 1.560068)
			(stroke
				(width 0.1)
				(type default)
			)
			(layer "F.Fab")
		)
		(pad "D" smd rect
			(at 1.100074 0 270)
			(size 1.016 1.4224)
			(layers "F.Cu" "F.Mask" "F.Paste")
			(net "PVDDCR_SOC_P1_EN_GD")
		)
		(pad "G" smd rect
			(at -1.100074 -0.94996 270)
			(size 1.016 1.4224)
			(layers "F.Cu" "F.Mask" "F.Paste")
			(net "PVDDCR_SOC_P1_EN_RC")
		)
		(pad "S" smd rect
			(at -1.100074 0.94996 270)
			(size 1.016 1.4224)
			(layers "F.Cu" "F.Mask" "F.Paste")
			(net "GND")
		)
	)
)
